# SCM (Grand Teton) — schematic netlist excerpt (pin names and nets, part order shuffled) for the footprints in the layout excerpt that follows; sources: Cadence DE-HDL packaged netlist, KiCad conversion of 12092022_DA0F0TMDCD0_F0T_Management_Board_D_brd_V3_OCP.brd

J4  SCONN67_NASA0S6730TS67  SCONN67_NASA0-S6730-TS67 IO  pkg CON_F67S2H2D2S_P0-5W7-55_LUVXM  page 21
  \1\  = GND
  \2\  = P3V3_AUX
  \3\  = SPI_BMC_BT_WP1_N_R
  \4\  = P3V3_AUX
  \5\  = SPI_BMC_BT_WP0_N_R
  \6\  = NC
  \7\  = GND
  \16\  = BSM_PRSNT_N
  \17\  = NC
  \18\  = GND
  \19\  = RST_SPI_BMC_FLASH_R2_N
  \20\  = NC
  \21\  = RST_SPI_BMC_FLASH_R1_N
  \22\  = NC
  \23\  = GND
  \24\  = GND
  \25\  = SPI_BMC_IO1_FLASH_R
  \26\  = SPI_BMC_HOLD1_N
  \27\  = SPI_BMC_IO0_FLASH_R
  \28\  = SPI_BMC_HOLD0_N
  \29\  = GND
  \30\  = GND
  \31\  = SPI_BMC_CLK_FLASH_R
  \32\  = NC
  \33\  = GND
  \34\  = NC
  \35\  = SPI_BMC_CS1_FLASH_R_N
  \36\  = GND
  \37\  = SPI_BMC_CS0_FLASH_R_N
  \38\  = NC
  \39\  = GND
  \40\  = SMB_BMC_MM16_R1_SCL
  \41\  = NC
  \42\  = SMB_BMC_MM16_R1_SDA
  \43\  = NC
  \44\  = NC
  \45\  = GND
  \46\  = EMMC_WP
  \47\  = NC
  \48\  = NC
  \49\  = NC
  \50\  = NC
  \51\  = GND
  \52\  = EMMC_DT7_R
  \53\  = NC
  \54\  = EMMC_DT6_R
  \55\  = EMMC_CLK_R
  \56\  = EMMC_DT5_R
  \57\  = GND
  \58\  = EMMC_DT4_R
  \59\  = EMMC_CMD_R
  \60\  = NC
  \61\  = EMMC_DT3_R
  \62\  = NC
  \63\  = GND
  \64\  = NC
  \65\  = EMMC_DT2_R
  \66\  = BMC_EMMC_RST_N
  \67\  = EMMC_DT1_R
  \68\  = NC
  \69\  = GND
  \70\  = NC
  \71\  = EMMC_DT0_R
  \72\  = P3V3_AUX
  \73\  = NC
  \74\  = P3V3_AUX
  \75\  = GND
  G1  = GND
  G2  = GND

(kicad_pcb
	(version 20260206)
	(generator "pcbnew")
	(generator_version "10.0")
	(general
		(thickness 1.6)
		(legacy_teardrops no)
	)
	(paper "A4")
	(title_block
		(title "12092022_DA0F0TMDCD0_F0T_Management_Board_D_brd_V3_OCP.brd")
		(comment 1 "Grand Teton / footprint 610 of 1440 (J4), pads 1-49 of 71")
	)
	(layers
		(0 "F.Cu" signal "TOP")
		(4 "In1.Cu" signal "GND")
		(6 "In2.Cu" signal "IN1")
		(8 "In3.Cu" signal "GND1")
		(10 "In4.Cu" signal "IN2")
		(12 "In5.Cu" signal "VCC")
		(14 "In6.Cu" signal "VCC1")
		(16 "In7.Cu" signal "IN3")
		(18 "In8.Cu" signal "GND2")
		(20 "In9.Cu" signal "IN4")
		(22 "In10.Cu" signal "GND3")
		(2 "B.Cu" signal "BOTTOM")
		(9 "F.Adhes" user "F.Adhesive")
		(11 "B.Adhes" user "B.Adhesive")
		(13 "F.Paste" user "Package Geometry/Pastemask Top")
		(15 "B.Paste" user "Package Geometry/Pastemask Bottom")
		(5 "F.SilkS" user "Ref Des/Silkscreen Top")
		(7 "B.SilkS" user "Ref Des/Silkscreen Bottom")
		(1 "F.Mask" user "Board Geometry/Soldermask Top")
		(3 "B.Mask" user "Board Geometry/Soldermask Bottom")
		(17 "Dwgs.User" user "User.Drawings")
		(19 "Cmts.User" user "User.Comments")
		(21 "Eco1.User" user "User.Eco1")
		(23 "Eco2.User" user "User.Eco2")
		(25 "Edge.Cuts" user "Board Geometry/Outline")
		(27 "Margin" user)
		(31 "F.CrtYd" user "Package Geometry/Place Bound Top")
		(29 "B.CrtYd" user "Package Geometry/Place Bound Bottom")
		(35 "F.Fab" user "Ref Des/Assembly Top")
		(33 "B.Fab" user "Ref Des/Assembly Bottom")
	)
	(footprint ""
		(layer "F.Cu")
		(at 26.75001 -77.16012 90)
		(property "Reference" "J4"
			(at -3.798062 -11.674348 90)
			(unlocked yes)
			(layer "F.SilkS")
			(effects
				(font
					(size 0.7874 0.5842)
					(thickness 0.1524)
				)
				(justify left)
			)
		)
		(property "Value" ""
			(at 0 0 90)
			(layer "F.Fab")
			(effects
				(font
					(size 1.27 1.27)
				)
			)
		)
		(duplicate_pad_numbers_are_jumpers no)
		(pad "" np_thru_hole circle
			(at -1.525016 -9.99998 90)
			(size 1.2192 1.2192)
			(drill 1.2192)
			(layers "*.Cu" "*.Mask")
			(clearance 0.381)
			(thermal_gap 0.381)
		)
		(pad "" np_thru_hole circle
			(at -1.525016 9.99998 90)
			(size 1.7018 1.7018)
			(drill 1.7018)
			(layers "*.Cu" "*.Mask")
			(clearance 0.381)
			(thermal_gap 0.381)
		)
		(pad "1" smd rect
			(at 3.750056 -9.249918)
			(size 0.2794 1.6002)
			(layers "F.Cu" "F.Mask" "F.Paste")
			(net "GND")
		)
		(pad "2" smd rect
			(at -3.799586 -8.999982)
			(size 0.2794 1.6002)
			(layers "F.Cu" "F.Mask" "F.Paste")
			(net "P3V3_AUX")
		)
		(pad "3" smd rect
			(at 3.750056 -8.750046)
			(size 0.2794 1.6002)
			(layers "F.Cu" "F.Mask" "F.Paste")
			(net "SPI_BMC_BT_WP1_N_R")
		)
		(pad "4" smd rect
			(at -3.799586 -8.50011)
			(size 0.2794 1.6002)
			(layers "F.Cu" "F.Mask" "F.Paste")
			(net "P3V3_AUX")
		)
		(pad "5" smd rect
			(at 3.750056 -8.24992)
			(size 0.2794 1.6002)
			(layers "F.Cu" "F.Mask" "F.Paste")
			(net "SPI_BMC_BT_WP0_N_R")
		)
		(pad "6" smd rect
			(at -3.799586 -7.999984)
			(size 0.2794 1.6002)
			(layers "F.Cu" "F.Mask" "F.Paste")
			(net "Net_1207")
		)
		(pad "7" smd rect
			(at 3.750056 -7.750048)
			(size 0.2794 1.6002)
			(layers "F.Cu" "F.Mask" "F.Paste")
			(net "GND")
		)
		(pad "16" smd rect
			(at -3.799586 -5.500116)
			(size 0.2794 1.6002)
			(layers "F.Cu" "F.Mask" "F.Paste")
			(net "BSM_PRSNT_N")
		)
		(pad "17" smd rect
			(at 3.750056 -5.249926)
			(size 0.2794 1.6002)
			(layers "F.Cu" "F.Mask" "F.Paste")
			(net "Net_1221")
		)
		(pad "18" smd rect
			(at -3.799586 -4.99999)
			(size 0.2794 1.6002)
			(layers "F.Cu" "F.Mask" "F.Paste")
			(net "GND")
		)
		(pad "19" smd rect
			(at 3.750056 -4.750054)
			(size 0.2794 1.6002)
			(layers "F.Cu" "F.Mask" "F.Paste")
			(net "RST_SPI_BMC_FLASH_R2_N")
		)
		(pad "20" smd rect
			(at -3.799586 -4.500118)
			(size 0.2794 1.6002)
			(layers "F.Cu" "F.Mask" "F.Paste")
			(net "Net_1220")
		)
		(pad "21" smd rect
			(at 3.750056 -4.249928)
			(size 0.2794 1.6002)
			(layers "F.Cu" "F.Mask" "F.Paste")
			(net "RST_SPI_BMC_FLASH_R1_N")
		)
		(pad "22" smd rect
			(at -3.799586 -3.999992)
			(size 0.2794 1.6002)
			(layers "F.Cu" "F.Mask" "F.Paste")
			(net "Net_1219")
		)
		(pad "23" smd rect
			(at 3.750056 -3.750056)
			(size 0.2794 1.6002)
			(layers "F.Cu" "F.Mask" "F.Paste")
			(net "GND")
		)
		(pad "24" smd rect
			(at -3.799586 -3.50012)
			(size 0.2794 1.6002)
			(layers "F.Cu" "F.Mask" "F.Paste")
			(net "GND")
		)
		(pad "25" smd rect
			(at 3.750056 -3.24993)
			(size 0.2794 1.6002)
			(layers "F.Cu" "F.Mask" "F.Paste")
			(net "SPI_BMC_IO1_FLASH_R")
		)
		(pad "26" smd rect
			(at -3.799586 -2.999994)
			(size 0.2794 1.6002)
			(layers "F.Cu" "F.Mask" "F.Paste")
			(net "SPI_BMC_HOLD1_N")
		)
		(pad "27" smd rect
			(at 3.750056 -2.750058)
			(size 0.2794 1.6002)
			(layers "F.Cu" "F.Mask" "F.Paste")
			(net "SPI_BMC_IO0_FLASH_R")
		)
		(pad "28" smd rect
			(at -3.799586 -2.500122)
			(size 0.2794 1.6002)
			(layers "F.Cu" "F.Mask" "F.Paste")
			(net "SPI_BMC_HOLD0_N")
		)
		(pad "29" smd rect
			(at 3.750056 -2.249932)
			(size 0.2794 1.6002)
			(layers "F.Cu" "F.Mask" "F.Paste")
			(net "GND")
		)
		(pad "30" smd rect
			(at -3.799586 -1.999996)
			(size 0.2794 1.6002)
			(layers "F.Cu" "F.Mask" "F.Paste")
			(net "GND")
		)
		(pad "31" smd rect
			(at 3.750056 -1.75006)
			(size 0.2794 1.6002)
			(layers "F.Cu" "F.Mask" "F.Paste")
			(net "SPI_BMC_CLK_FLASH_R")
		)
		(pad "32" smd rect
			(at -3.799586 -1.500124)
			(size 0.2794 1.6002)
			(layers "F.Cu" "F.Mask" "F.Paste")
			(net "Net_1218")
		)
		(pad "33" smd rect
			(at 3.750056 -1.249934)
			(size 0.2794 1.6002)
			(layers "F.Cu" "F.Mask" "F.Paste")
			(net "GND")
		)
		(pad "34" smd rect
			(at -3.799586 -0.999998)
			(size 0.2794 1.6002)
			(layers "F.Cu" "F.Mask" "F.Paste")
			(net "Net_1217")
		)
		(pad "35" smd rect
			(at 3.750056 -0.750062)
			(size 0.2794 1.6002)
			(layers "F.Cu" "F.Mask" "F.Paste")
			(net "SPI_BMC_CS1_FLASH_R_N")
		)
		(pad "36" smd rect
			(at -3.799586 -0.499872)
			(size 0.2794 1.6002)
			(layers "F.Cu" "F.Mask" "F.Paste")
			(net "GND")
		)
		(pad "37" smd rect
			(at 3.750056 -0.249936)
			(size 0.2794 1.6002)
			(layers "F.Cu" "F.Mask" "F.Paste")
			(net "SPI_BMC_CS0_FLASH_R_N")
		)
		(pad "38" smd rect
			(at -3.799586 0)
			(size 0.2794 1.6002)
			(layers "F.Cu" "F.Mask" "F.Paste")
			(net "Net_1216")
		)
		(pad "39" smd rect
			(at 3.750056 0.249936)
			(size 0.2794 1.6002)
			(layers "F.Cu" "F.Mask" "F.Paste")
			(net "GND")
		)
		(pad "40" smd rect
			(at -3.799586 0.499872)
			(size 0.2794 1.6002)
			(layers "F.Cu" "F.Mask" "F.Paste")
			(net "SMB_BMC_MM16_R1_SCL")
		)
		(pad "41" smd rect
			(at 3.750056 0.750062)
			(size 0.2794 1.6002)
			(layers "F.Cu" "F.Mask" "F.Paste")
			(net "Net_1215")
		)
		(pad "42" smd rect
			(at -3.799586 0.999998)
			(size 0.2794 1.6002)
			(layers "F.Cu" "F.Mask" "F.Paste")
			(net "SMB_BMC_MM16_R1_SDA")
		)
		(pad "43" smd rect
			(at 3.750056 1.249934)
			(size 0.2794 1.6002)
			(layers "F.Cu" "F.Mask" "F.Paste")
			(net "Net_1214")
		)
		(pad "44" smd rect
			(at -3.799586 1.500124)
			(size 0.2794 1.6002)
			(layers "F.Cu" "F.Mask" "F.Paste")
			(net "Net_1213")
		)
		(pad "45" smd rect
			(at 3.750056 1.75006)
			(size 0.2794 1.6002)
			(layers "F.Cu" "F.Mask" "F.Paste")
			(net "GND")
		)
		(pad "46" smd rect
			(at -3.799586 1.999996)
			(size 0.2794 1.6002)
			(layers "F.Cu" "F.Mask" "F.Paste")
			(net "EMMC_WP")
		)
		(pad "47" smd rect
			(at 3.750056 2.249932)
			(size 0.2794 1.6002)
			(layers "F.Cu" "F.Mask" "F.Paste")
			(net "Net_1212")
		)
		(pad "48" smd rect
			(at -3.799586 2.500122)
			(size 0.2794 1.6002)
			(layers "F.Cu" "F.Mask" "F.Paste")
			(net "Net_1211")
		)
		(pad "49" smd rect
			(at 3.750056 2.750058)
			(size 0.2794 1.6002)
			(layers "F.Cu" "F.Mask" "F.Paste")
			(net "Net_1210")
		)
		(pad "50" smd rect
			(at -3.799586 2.999994)
			(size 0.2794 1.6002)
			(layers "F.Cu" "F.Mask" "F.Paste")
			(net "Net_1209")
		)
		(pad "51" smd rect
			(at 3.750056 3.24993)
			(size 0.2794 1.6002)
			(layers "F.Cu" "F.Mask" "F.Paste")
			(net "GND")
		)
		(pad "52" smd rect
			(at -3.799586 3.50012)
			(size 0.2794 1.6002)
			(layers "F.Cu" "F.Mask" "F.Paste")
			(net "EMMC_DT7_R")
		)
		(pad "53" smd rect
			(at 3.750056 3.750056)
			(size 0.2794 1.6002)
			(layers "F.Cu" "F.Mask" "F.Paste")
			(net "Net_1208")
		)
		(pad "54" smd rect
			(at -3.799586 3.999992)
			(size 0.2794 1.6002)
			(layers "F.Cu" "F.Mask" "F.Paste")
			(net "EMMC_DT6_R")
		)
		(pad "55" smd rect
			(at 3.750056 4.249928)
			(size 0.2794 1.6002)
			(layers "F.Cu" "F.Mask" "F.Paste")
			(net "EMMC_CLK_R")
		)
	)
)
